(kicad_pcb
	(version 20260206)
	(generator "pcbnew")
	(generator_version "10.0")
	(general
		(thickness 1.21888)
		(legacy_teardrops no)
	)
	(paper "A4")
	(title_block
		(title "timecard-v9 — TimeCard-DC-V9_EXP.PcbDoc")
		(comment 1 "Time Appliance Project (Time Card) / footprints 29-41 of 402")
	)
	(layers
		(0 "F.Cu" signal "TOP")
		(4 "In1.Cu" signal "SGND")
		(6 "In2.Cu" signal "IN1")
		(8 "In3.Cu" signal "IN2")
		(10 "In4.Cu" signal "SGND1")
		(2 "B.Cu" signal "BOTTOM")
		(9 "F.Adhes" user "F.Adhesive")
		(11 "B.Adhes" user "B.Adhesive")
		(13 "F.Paste" user "Top Paste")
		(15 "B.Paste" user "Bottom Paste")
		(5 "F.SilkS" user "Top Overlay")
		(7 "B.SilkS" user "Bottom Overlay")
		(1 "F.Mask" user "Top Solder")
		(3 "B.Mask" user "Bottom Solder")
		(17 "Dwgs.User" user "User.Drawings")
		(19 "Cmts.User" user "User.Comments")
		(21 "Eco1.User" user "User.Eco1")
		(23 "Eco2.User" user "User.Eco2")
		(25 "Edge.Cuts" user)
		(27 "Margin" user)
		(31 "F.CrtYd" user "Top Courtyard")
		(29 "B.CrtYd" user "Bottom Courtyard")
		(35 "F.Fab" user "Top Component Center")
		(33 "B.Fab" user "Bottom Component Center")
	)
	(footprint "Vault:FP-0603-L_1_6_0_2-W_0_8_0-MFG"
		(layer "F.Cu")
		(at 169.4716 83.5162 90)
		(property "Reference" "C80"
			(at 2.7286 -0.023069 90)
			(unlocked yes)
			(layer "F.SilkS")
			(effects
				(font
					(size 0.762 0.762)
					(thickness 0.2286)
				)
			)
		)
		(property "Value" "10uF_16V_0603"
			(at -2.871951 8.95046 0)
			(unlocked yes)
			(layer "F.SilkS")
			(hide yes)
			(effects
				(font
					(size 0.762 0.762)
					(thickness 0.2286)
				)
			)
		)
		(sheetname "03-POWER")
		(sheetfile "03-POWER.kicad_sch")
		(duplicate_pad_numbers_are_jumpers no)
		(fp_line
			(start -0.9 -0.825)
			(end 0.9 -0.825)
			(stroke
				(width 0.2)
				(type solid)
			)
			(layer "F.SilkS")
		)
		(fp_line
			(start -0.9 0.82499)
			(end 0.9 0.82499)
			(stroke
				(width 0.2)
				(type solid)
			)
			(layer "F.SilkS")
		)
		(fp_line
			(start 1.15 -0.6)
			(end 1.15 0.59999)
			(stroke
				(width 0.2)
				(type solid)
			)
			(layer "F.CrtYd")
		)
		(fp_line
			(start -1.15 -0.6)
			(end 1.15 -0.6)
			(stroke
				(width 0.2)
				(type solid)
			)
			(layer "F.CrtYd")
		)
		(fp_line
			(start -1.15 -0.6)
			(end -1.15 0.59999)
			(stroke
				(width 0.2)
				(type solid)
			)
			(layer "F.CrtYd")
		)
		(fp_line
			(start -1.15 0.59999)
			(end 1.15 0.59999)
			(stroke
				(width 0.2)
				(type solid)
			)
			(layer "F.CrtYd")
		)
		(fp_line
			(start 1.15 -0.6)
			(end 1.15 0.59999)
			(stroke
				(width 0.2)
				(type solid)
			)
			(layer "F.Fab")
		)
		(fp_line
			(start -1.15 -0.6)
			(end 1.15 -0.6)
			(stroke
				(width 0.2)
				(type solid)
			)
			(layer "F.Fab")
		)
		(fp_line
			(start -1.15 -0.6)
			(end -1.15 0.59999)
			(stroke
				(width 0.2)
				(type solid)
			)
			(layer "F.Fab")
		)
		(fp_line
			(start 0 -0.5)
			(end 0 0.49999)
			(stroke
				(width 0.1)
				(type solid)
			)
			(layer "F.Fab")
		)
		(fp_line
			(start -0.5 0)
			(end 0.5 0)
			(stroke
				(width 0.1)
				(type solid)
			)
			(layer "F.Fab")
		)
		(fp_line
			(start -1.15 0.59999)
			(end 1.15 0.59999)
			(stroke
				(width 0.2)
				(type solid)
			)
			(layer "F.Fab")
		)
		(fp_text user "${REFERENCE}"
			(at -0.00001 0.09601 90)
			(unlocked yes)
			(layer "F.Fab")
			(effects
				(font
					(face "Arial")
					(size 0.63 0.63)
					(thickness 0.1)
				)
				(justify left bottom)
			)
		)
		(pad "1" smd rect
			(at -0.7 0 90)
			(size 0.7 0.7)
			(layers "F.Cu" "F.Mask" "F.Paste")
			(net "+3.3V")
			(solder_mask_margin 0)
			(solder_paste_margin 0)
		)
		(pad "2" smd rect
			(at 0.7 0 90)
			(size 0.7 0.7)
			(layers "F.Cu" "F.Mask" "F.Paste")
			(net "GND")
			(solder_mask_margin 0)
			(solder_paste_margin 0)
		)
	)
	(footprint ""
		(layer "F.Cu")
		(at 208.22161 83.61617)
		(property "Reference" ""
			(at 0 0 0)
			(layer "F.SilkS")
			(effects
				(font
					(size 1.27 1.27)
				)
			)
		)
		(property "Value" ""
			(at 0 0 0)
			(layer "F.Fab")
			(effects
				(font
					(size 1.27 1.27)
				)
			)
		)
		(duplicate_pad_numbers_are_jumpers no)
		(pad "2" thru_hole circle
			(at 0 0)
			(size 6.5 6.5)
			(drill 4.2)
			(layers "*.Cu" "*.Mask")
			(remove_unused_layers no)
			(net "GND")
			(thermal_bridge_angle 90)
		)
	)
	(footprint "Vault:RESC3216X89X64NL25T25"
		(layer "F.Cu")
		(at 172.2466 85.8162 180)
		(property "Reference" "R72"
			(at 3.1964 -0.126921 0)
			(unlocked yes)
			(layer "F.SilkS")
			(effects
				(font
					(size 0.762 0.762)
					(thickness 0.2286)
				)
			)
		)
		(property "Value" "2mOhm_1%_1206"
			(at 7.62962 3.037071 180)
			(unlocked yes)
			(layer "F.SilkS")
			(hide yes)
			(effects
				(font
					(size 0.762 0.762)
					(thickness 0.2286)
				)
			)
		)
		(sheetname "03-POWER")
		(sheetfile "03-POWER.kicad_sch")
		(duplicate_pad_numbers_are_jumpers no)
		(fp_line
			(start 0.2 0.825)
			(end -0.2 0.825)
			(stroke
				(width 0.2)
				(type solid)
			)
			(layer "F.SilkS")
		)
		(fp_line
			(start 0.2 -0.825)
			(end -0.2 -0.825)
			(stroke
				(width 0.2)
				(type solid)
			)
			(layer "F.SilkS")
		)
		(pad "1" smd rect
			(at -1.325 0 270)
			(size 1.85 1.5)
			(layers "F.Cu" "F.Mask" "F.Paste")
			(net "P3V3_SENSE")
		)
		(pad "2" smd rect
			(at 1.325 0 270)
			(size 1.85 1.5)
			(layers "F.Cu" "F.Mask" "F.Paste")
			(net "+3.3V")
		)
	)
	(footprint "Capacitors:CAPC2012X14N"
		(layer "F.Cu")
		(at 138.7854 84.7662 90)
		(property "Reference" "C62"
			(at 1.446695 -1.09139 0)
			(unlocked yes)
			(layer "F.SilkS")
			(effects
				(font
					(size 0.762 0.762)
					(thickness 0.2286)
				)
				(justify left bottom)
			)
		)
		(property "Value" "CAP_0805_10UF_25V"
			(at -2.433445 -1.7875 0)
			(unlocked yes)
			(layer "F.SilkS")
			(hide yes)
			(effects
				(font
					(size 0.762 0.762)
					(thickness 0.2286)
				)
				(justify left bottom)
			)
		)
		(sheetname "06-MAC")
		(sheetfile "06-MAC.kicad_sch")
		(duplicate_pad_numbers_are_jumpers no)
		(fp_line
			(start -0.762 -0.9652)
			(end 0.762 -0.9652)
			(stroke
				(width 0.1524)
				(type solid)
			)
			(layer "F.SilkS")
		)
		(fp_line
			(start -0.762 0.9652)
			(end 0.762 0.9652)
			(stroke
				(width 0.1524)
				(type solid)
			)
			(layer "F.SilkS")
		)
		(pad "1" smd rect
			(at -0.9 0 180)
			(size 1.45 1.15)
			(layers "F.Cu" "F.Mask" "F.Paste")
			(net "MAC_VCC")
		)
		(pad "2" smd rect
			(at 0.9 0 180)
			(size 1.45 1.15)
			(layers "F.Cu" "F.Mask" "F.Paste")
			(net "GND")
		)
	)
	(footprint "Vault:RESC1005X40X25NL05T05"
		(layer "F.Cu")
		(at 193.2216 128.8162 90)
		(property "Reference" "R154"
			(at 0.9032 -2.473079 90)
			(unlocked yes)
			(layer "F.SilkS")
			(effects
				(font
					(size 0.762 0.762)
					(thickness 0.2032)
				)
			)
		)
		(property "Value" "DNI_27_1%_0402"
			(at -2.732271 10.270965 0)
			(unlocked yes)
			(layer "F.SilkS")
			(hide yes)
			(effects
				(font
					(size 0.762 0.762)
					(thickness 0.2032)
				)
			)
		)
		(sheetname "11-M2_RCB_MUX")
		(sheetfile "11-M2_RCB_MUX.kicad_sch")
		(duplicate_pad_numbers_are_jumpers no)
		(pad "1" smd rect
			(at -0.45 0 180)
			(size 0.55 0.55)
			(layers "F.Cu" "F.Mask" "F.Paste")
			(net "M2_GPS2_TX")
		)
		(pad "2" smd rect
			(at 0.45 0 180)
			(size 0.55 0.55)
			(layers "F.Cu" "F.Mask" "F.Paste")
			(net "GPS2_TX")
		)
	)
	(footprint "Vault:RESC1005X40X25NL05T05"
		(layer "F.Cu")
		(at 169.3216 118.1162 90)
		(property "Reference" "R121"
			(at -3.4032 -0.652001 270)
			(unlocked yes)
			(layer "F.SilkS")
			(effects
				(font
					(size 0.762 0.762)
					(thickness 0.2032)
				)
			)
		)
		(property "Value" "27_1%_0402"
			(at -2.732271 7.35092 0)
			(unlocked yes)
			(layer "F.SilkS")
			(hide yes)
			(effects
				(font
					(size 0.762 0.762)
					(thickness 0.2032)
				)
			)
		)
		(sheetname "08-DIPSwitches_I2C")
		(sheetfile "08-DIPSwitches_I2C.kicad_sch")
		(duplicate_pad_numbers_are_jumpers no)
		(pad "1" smd rect
			(at -0.45 0 180)
			(size 0.55 0.55)
			(layers "F.Cu" "F.Mask" "F.Paste")
			(net "PCIE_PERST")
		)
		(pad "2" smd rect
			(at 0.45 0 180)
			(size 0.55 0.55)
			(layers "F.Cu" "F.Mask" "F.Paste")
			(net "NetR121_2")
		)
	)
	(footprint "Vault:FP-LTST-C191KGKT-MFG"
		(layer "F.Cu")
		(at 224.7216 114.3162)
		(property "Reference" "D21"
			(at -3.392175 0.026931 0)
			(unlocked yes)
			(layer "F.SilkS")
			(effects
				(font
					(size 0.762 0.762)
					(thickness 0.2286)
				)
			)
		)
		(property "Value" "LTST-C191KGKT"
			(at 7.09647 2.452871 0)
			(unlocked yes)
			(layer "F.SilkS")
			(hide yes)
			(effects
				(font
					(size 0.762 0.762)
					(thickness 0.2286)
				)
			)
		)
		(sheetname "08-DIPSwitches_I2C")
		(sheetfile "08-DIPSwitches_I2C.kicad_sch")
		(duplicate_pad_numbers_are_jumpers no)
		(fp_line
			(start -0.85 -0.775)
			(end 0.85 -0.775)
			(stroke
				(width 0.2)
				(type solid)
			)
			(layer "F.SilkS")
		)
		(fp_line
			(start -0.85 0.775)
			(end 0.85 0.775)
			(stroke
				(width 0.2)
				(type solid)
			)
			(layer "F.SilkS")
		)
		(fp_circle
			(center -1.7 0)
			(end -1.7 -0.125)
			(stroke
				(width 0.25)
				(type solid)
			)
			(fill no)
			(layer "F.SilkS")
		)
		(fp_line
			(start -1.25 -0.55)
			(end 1.25 -0.55)
			(stroke
				(width 0.2)
				(type solid)
			)
			(layer "F.CrtYd")
		)
		(fp_line
			(start -1.25 0.55)
			(end -1.25 -0.55)
			(stroke
				(width 0.2)
				(type solid)
			)
			(layer "F.CrtYd")
		)
		(fp_line
			(start -1.25 0.55)
			(end 1.25 0.55)
			(stroke
				(width 0.2)
				(type solid)
			)
			(layer "F.CrtYd")
		)
		(fp_line
			(start 1.25 0.55)
			(end 1.25 -0.55)
			(stroke
				(width 0.2)
				(type solid)
			)
			(layer "F.CrtYd")
		)
		(fp_line
			(start -1.25 -0.55)
			(end 1.25 -0.55)
			(stroke
				(width 0.2)
				(type solid)
			)
			(layer "F.Fab")
		)
		(fp_line
			(start -1.25 0.55)
			(end -1.25 -0.55)
			(stroke
				(width 0.2)
				(type solid)
			)
			(layer "F.Fab")
		)
		(fp_line
			(start -1.25 0.55)
			(end 1.25 0.55)
			(stroke
				(width 0.2)
				(type solid)
			)
			(layer "F.Fab")
		)
		(fp_line
			(start -0.5 0)
			(end 0.5 0)
			(stroke
				(width 0.1)
				(type solid)
			)
			(layer "F.Fab")
		)
		(fp_line
			(start 0 0.5)
			(end 0 -0.5)
			(stroke
				(width 0.1)
				(type solid)
			)
			(layer "F.Fab")
		)
		(fp_line
			(start 1.25 0.55)
			(end 1.25 -0.55)
			(stroke
				(width 0.2)
				(type solid)
			)
			(layer "F.Fab")
		)
		(fp_text user "${REFERENCE}"
			(at 0 0.29534 0)
			(unlocked yes)
			(layer "F.Fab")
			(effects
				(font
					(face "Arial")
					(size 0.63 0.63)
					(thickness 0.1)
				)
				(justify left bottom)
			)
		)
		(pad "1" smd rect
			(at -0.75 0)
			(size 0.8 0.8)
			(layers "F.Cu" "F.Mask" "F.Paste")
			(net "NetD21_1")
			(solder_mask_margin 0)
			(solder_paste_margin 0)
		)
		(pad "2" smd rect
			(at 0.75 0)
			(size 0.8 0.8)
			(layers "F.Cu" "F.Mask" "F.Paste")
			(net "+3.3V")
			(solder_mask_margin 0)
			(solder_paste_margin 0)
		)
	)
	(footprint "Passives:SOT65P210X110-3N"
		(layer "F.Cu")
		(at 191.1826 145.69763)
		(property "Reference" "D6"
			(at -3.16026 -1.068085 0)
			(unlocked yes)
			(layer "F.SilkS")
			(effects
				(font
					(size 0.762 0.762)
					(thickness 0.2286)
				)
				(justify left bottom)
			)
		)
		(property "Value" "BAT54SW"
			(at -4.0249 -1.823555 0)
			(unlocked yes)
			(layer "F.SilkS")
			(hide yes)
			(effects
				(font
					(size 0.762 0.762)
					(thickness 0.2286)
				)
				(justify left bottom)
			)
		)
		(sheetname "04-PCIe_JTAG")
		(sheetfile "04-PCIe_JTAG.kicad_sch")
		(duplicate_pad_numbers_are_jumpers no)
		(fp_line
			(start -0.32499 -1.1)
			(end 0.675 -1.1)
			(stroke
				(width 0.2)
				(type solid)
			)
			(layer "F.SilkS")
		)
		(fp_line
			(start -0.32499 1.1)
			(end 0.675 1.1)
			(stroke
				(width 0.2)
				(type solid)
			)
			(layer "F.SilkS")
		)
		(fp_line
			(start 0.675 -0.65)
			(end 0.675 -1.1)
			(stroke
				(width 0.2)
				(type solid)
			)
			(layer "F.SilkS")
		)
		(fp_line
			(start 0.675 1.1)
			(end 0.675 0.65)
			(stroke
				(width 0.2)
				(type solid)
			)
			(layer "F.SilkS")
		)
		(fp_circle
			(center -1.125 -1.45)
			(end -1.125 -1.575)
			(stroke
				(width 0.25)
				(type solid)
			)
			(fill no)
			(layer "F.SilkS")
		)
		(pad "1" smd rect
			(at -1.125 -0.65 90)
			(size 0.5 0.9)
			(layers "F.Cu" "F.Mask" "F.Paste")
			(net "GND")
		)
		(pad "2" smd rect
			(at -1.125 0.65 90)
			(size 0.5 0.9)
			(layers "F.Cu" "F.Mask" "F.Paste")
			(net "+3.3V")
		)
		(pad "3" smd rect
			(at 1.125 0 90)
			(size 0.5 0.9)
			(layers "F.Cu" "F.Mask" "F.Paste")
			(net "FPGA_TDO")
		)
	)
	(footprint "Vault:RESC1005X40X25NL05T05"
		(layer "F.Cu")
		(at 161.1716 128.4162 180)
		(property "Reference" "R84"
			(at -0.4786 1.073069 0)
			(unlocked yes)
			(layer "F.SilkS")
			(effects
				(font
					(size 0.762 0.762)
					(thickness 0.2286)
				)
			)
		)
		(property "Value" "27_1%_0402"
			(at -2.732271 7.37632 90)
			(unlocked yes)
			(layer "F.SilkS")
			(hide yes)
			(effects
				(font
					(size 0.762 0.762)
					(thickness 0.2286)
				)
			)
		)
		(sheetname "09-USBUart_PPSMUX_UARTMUX")
		(sheetfile "09-USBUart_PPSMUX_UARTMUX.kicad_sch")
		(duplicate_pad_numbers_are_jumpers no)
		(pad "1" smd rect
			(at -0.45 0 270)
			(size 0.55 0.55)
			(layers "F.Cu" "F.Mask" "F.Paste")
			(net "GND")
		)
		(pad "2" smd rect
			(at 0.45 0 270)
			(size 0.55 0.55)
			(layers "F.Cu" "F.Mask" "F.Paste")
			(net "NetR84_2")
		)
	)
	(footprint "Vault:RESC1005X40X25LL05T10"
		(layer "F.Cu")
		(at 143.1216 107.4162 90)
		(property "Reference" "R97"
			(at -2.2286 -0.026931 270)
			(unlocked yes)
			(layer "F.SilkS")
			(effects
				(font
					(size 0.762 0.762)
					(thickness 0.2286)
				)
			)
		)
		(property "Value" "49.9_1%_0402"
			(at -2.579871 8.823665 0)
			(unlocked yes)
			(layer "F.SilkS")
			(hide yes)
			(effects
				(font
					(size 0.762 0.762)
					(thickness 0.2286)
				)
			)
		)
		(sheetname "09-USBUart_PPSMUX_UARTMUX")
		(sheetfile "09-USBUart_PPSMUX_UARTMUX.kicad_sch")
		(duplicate_pad_numbers_are_jumpers no)
		(pad "1" smd rect
			(at -0.375 0 180)
			(size 0.45 0.5)
			(layers "F.Cu" "F.Mask" "F.Paste")
			(net "FPGA_MAC_PPSDIFF_OUT")
		)
		(pad "2" smd rect
			(at 0.375 0 180)
			(size 0.45 0.5)
			(layers "F.Cu" "F.Mask" "F.Paste")
			(net "NetR97_2")
		)
	)
	(footprint "Vault:RESC1005X40X25NL05T05"
		(layer "F.Cu")
		(at 158.4216 132.1162)
		(property "Reference" "R101"
			(at 1.13007 0.988851 0)
			(unlocked yes)
			(layer "F.SilkS")
			(effects
				(font
					(size 0.762 0.762)
					(thickness 0.2286)
				)
			)
		)
		(property "Value" "DNI_27_1%_0402"
			(at -2.732281 10.296375 270)
			(unlocked yes)
			(layer "F.SilkS")
			(hide yes)
			(effects
				(font
					(size 0.762 0.762)
					(thickness 0.2286)
				)
			)
		)
		(sheetname "09-USBUart_PPSMUX_UARTMUX")
		(sheetfile "09-USBUart_PPSMUX_UARTMUX.kicad_sch")
		(duplicate_pad_numbers_are_jumpers no)
		(pad "1" smd rect
			(at -0.45 0 90)
			(size 0.55 0.55)
			(layers "F.Cu" "F.Mask" "F.Paste")
			(net "FTDI_TX")
		)
		(pad "2" smd rect
			(at 0.45 0 90)
			(size 0.55 0.55)
			(layers "F.Cu" "F.Mask" "F.Paste")
			(net "UART1_RXD")
		)
	)
	(footprint "Vault:RESC1005X40X25LL05T10"
		(layer "F.Cu")
		(at 144.2216 107.3662 90)
		(property "Reference" "R99"
			(at -2.4786 0.473069 270)
			(unlocked yes)
			(layer "F.SilkS")
			(effects
				(font
					(size 0.762 0.762)
					(thickness 0.2286)
				)
			)
		)
		(property "Value" "49.9_1%_0402"
			(at -2.579871 8.823665 0)
			(unlocked yes)
			(layer "F.SilkS")
			(hide yes)
			(effects
				(font
					(size 0.762 0.762)
					(thickness 0.2286)
				)
			)
		)
		(sheetname "09-USBUart_PPSMUX_UARTMUX")
		(sheetfile "09-USBUart_PPSMUX_UARTMUX.kicad_sch")
		(duplicate_pad_numbers_are_jumpers no)
		(pad "1" smd rect
			(at -0.375 0 180)
			(size 0.45 0.5)
			(layers "F.Cu" "F.Mask" "F.Paste")
			(net "FPGA_MAC_PPS_DIFF_IN0")
		)
		(pad "2" smd rect
			(at 0.375 0 180)
			(size 0.45 0.5)
			(layers "F.Cu" "F.Mask" "F.Paste")
			(net "NetR99_2")
		)
	)
	(footprint "SamacSys:155124M173200"
		(layer "F.Cu")
		(at 67.4466 114.8162 90)
		(property "Reference" "D16"
			(at -0.4286 1.448069 270)
			(unlocked yes)
			(layer "F.SilkS")
			(effects
				(font
					(size 0.762 0.762)
					(thickness 0.2286)
				)
			)
		)
		(property "Value" "155124M173200"
			(at 7.1471 2.605271 90)
			(unlocked yes)
			(layer "F.SilkS")
			(hide yes)
			(effects
				(font
					(size 0.762 0.762)
					(thickness 0.2286)
				)
			)
		)
		(sheetname "02-USER_IO_STATUS")
		(sheetfile "02-USER_IO_STATUS.kicad_sch")
		(duplicate_pad_numbers_are_jumpers no)
		(fp_line
			(start -0.8 0.5)
			(end 0.8 0.5)
			(stroke
				(width 0.1)
				(type solid)
			)
			(layer "F.SilkS")
		)
		(fp_arc
			(start -2 -0.1)
			(mid -1.95 -0.05)
			(end -2 0)
			(stroke
				(width 0.381)
				(type solid)
			)
			(layer "F.SilkS")
		)
		(fp_arc
			(start -2 0)
			(mid -2.05 -0.05)
			(end -2 -0.1)
			(stroke
				(width 0.381)
				(type solid)
			)
			(layer "F.SilkS")
		)
		(pad "1" smd rect
			(at -1.4 0 180)
			(size 0.9 0.6)
			(layers "F.Cu" "F.Mask" "F.Paste")
			(net "+3.3V")
		)
		(pad "2" smd rect
			(at -0.45 -0.325 90)
			(size 0.6 0.55)
			(layers "F.Cu" "F.Mask" "F.Paste")
			(net "NetD16_2")
		)
		(pad "3" smd rect
			(at 0.45 -0.325 90)
			(size 0.6 0.55)
			(layers "F.Cu" "F.Mask" "F.Paste")
			(net "NetD16_3")
		)
		(pad "4" smd rect
			(at 1.4 0 180)
			(size 0.9 0.6)
			(layers "F.Cu" "F.Mask" "F.Paste")
			(net "NetD16_4")
		)
	)
)
